# T6G (Grand Teton) — schematic netlist excerpt (pin names and nets, part order shuffled) for the footprints in the layout excerpt that follows; sources: Cadence DE-HDL packaged netlist, KiCad conversion of 04192023_DAF0TMB3IC0_F0TG_MB_C_brd_V02_OCP.brd

PU28  ISL99390FRZTR5935  ISL99390FRZ-TR5935 IC  pkg QFN21_6X5XB  page 212
  VOS  = PVDDCR_CPU0_P1_VOS4
  AGND  = GND
  VCC  = PVDDCR_CPU0_P1_VCC4
  PVCC  = PVDDCR_CPU0_P1_PVCC
  PGND1  = GND
  GL1  = NC_PVDDCR_CPU0_P1_GL1_4
  PGND2  = GND
  SW  = SW_PVDDCR_CPU0_P1_SW4
  VIN1  = SW_P12V_AUX_PVDDCR_CPU0_P1_FLT
  VIN2  = SW_P12V_AUX_PVDDCR_CPU0_P1_FLT
  DNC  = NC_PVDDCR_CPU0_P1_DNC4
  PHASE  = SW_PVDDCR_CPU0_P1_PH4
  BOOT  = SW_PVDDCR_CPU0_P1_BOOT4
  PWM  = PVDDCR_CPU0_P1_PWM4
  EN  = PVDDCR_CPU0_P1_VCC4
  TOUT_FLT  = PVDDCR_CPU0_P1_TEMP0
  LSET  = PVDDCR_CPU0_P1_LSET4
  IOUT  = PVDDCR_CPU0_P1_IMON4
  REFIN  = PVDDCR_CPU0_P1_VCCS
  PGND3  = GND
  GL2  = NC_PVDDCR_CPU0_P1_GL2_4

(kicad_pcb
	(version 20260206)
	(generator "pcbnew")
	(generator_version "10.0")
	(general
		(thickness 1.6)
		(legacy_teardrops no)
	)
	(paper "A4")
	(title_block
		(title "04192023_DAF0TMB3IC0_F0TG_MB_C_brd_V02_OCP.brd")
		(comment 1 "Grand Teton / footprints 239-239 of 8354")
	)
	(layers
		(0 "F.Cu" signal "TOP")
		(4 "In1.Cu" signal "GND")
		(6 "In2.Cu" signal "IN1")
		(8 "In3.Cu" signal "GND1")
		(10 "In4.Cu" signal "IN2")
		(12 "In5.Cu" signal "GND2")
		(14 "In6.Cu" signal "IN3")
		(16 "In7.Cu" signal "GND3")
		(18 "In8.Cu" signal "VCC")
		(20 "In9.Cu" signal "VCC1")
		(22 "In10.Cu" signal "GND4")
		(24 "In11.Cu" signal "IN4")
		(26 "In12.Cu" signal "GND5")
		(28 "In13.Cu" signal "IN5")
		(30 "In14.Cu" signal "GND6")
		(32 "In15.Cu" signal "IN6")
		(34 "In16.Cu" signal "GND7")
		(2 "B.Cu" signal "BOTTOM")
		(9 "F.Adhes" user "F.Adhesive")
		(11 "B.Adhes" user "B.Adhesive")
		(13 "F.Paste" user "Package Geometry/Pastemask Top")
		(15 "B.Paste" user "Package Geometry/Pastemask Bottom")
		(5 "F.SilkS" user "Ref Des/Silkscreen Top")
		(7 "B.SilkS" user "Ref Des/Silkscreen Bottom")
		(1 "F.Mask" user "Board Geometry/Soldermask Top")
		(3 "B.Mask" user "Board Geometry/Soldermask Bottom")
		(17 "Dwgs.User" user "User.Drawings")
		(19 "Cmts.User" user "User.Comments")
		(21 "Eco1.User" user "User.Eco1")
		(23 "Eco2.User" user "User.Eco2")
		(25 "Edge.Cuts" user "Board Geometry/Outline")
		(27 "Margin" user)
		(31 "F.CrtYd" user "Package Geometry/Place Bound Top")
		(29 "B.CrtYd" user "Package Geometry/Place Bound Bottom")
		(35 "F.Fab" user "Ref Des/Assembly Top")
		(33 "B.Fab" user "Ref Des/Assembly Bottom")
	)
	(footprint ""
		(layer "F.Cu")
		(at 107.45597 -178.171856 180)
		(property "Reference" "PU28"
			(at 5.34289 -4.788916 0)
			(unlocked yes)
			(layer "F.SilkS")
			(effects
				(font
					(size 0.7874 0.5842)
					(thickness 0.1524)
				)
				(justify left)
			)
		)
		(property "Value" ""
			(at 0 0 180)
			(layer "F.Fab")
			(effects
				(font
					(size 1.27 1.27)
				)
			)
		)
		(duplicate_pad_numbers_are_jumpers no)
		(fp_line
			(start 2.500122 2.999994)
			(end 2.2987 2.999994)
			(stroke
				(width 0.1524)
				(type default)
			)
			(layer "F.SilkS")
		)
		(fp_line
			(start 2.500122 2.339594)
			(end 2.500122 2.999994)
			(stroke
				(width 0.1524)
				(type default)
			)
			(layer "F.SilkS")
		)
		(fp_line
			(start 2.500122 -2.999994)
			(end 2.500122 -2.44348)
			(stroke
				(width 0.1524)
				(type default)
			)
			(layer "F.SilkS")
		)
		(fp_line
			(start 2.31394 -2.999994)
			(end 2.500122 -2.999994)
			(stroke
				(width 0.1524)
				(type default)
			)
			(layer "F.SilkS")
		)
		(fp_line
			(start -2.2987 2.999994)
			(end -2.500122 2.999994)
			(stroke
				(width 0.1524)
				(type default)
			)
			(layer "F.SilkS")
		)
		(fp_line
			(start -2.500122 2.999994)
			(end -2.500122 2.339594)
			(stroke
				(width 0.1524)
				(type default)
			)
			(layer "F.SilkS")
		)
		(fp_line
			(start -2.500122 0.6604)
			(end -2.500122 0.229108)
			(stroke
				(width 0.1524)
				(type default)
			)
			(layer "F.SilkS")
		)
		(fp_line
			(start -2.500122 -2.529078)
			(end -2.500122 -2.999994)
			(stroke
				(width 0.1524)
				(type default)
			)
			(layer "F.SilkS")
		)
		(fp_line
			(start -2.500122 -2.999994)
			(end -2.24409 -2.999994)
			(stroke
				(width 0.1524)
				(type default)
			)
			(layer "F.SilkS")
		)
		(fp_poly
			(pts
				(xy -2.819908 -2.401316) (xy -3.493262 -2.625852) (xy -3.044444 -3.074924)
			)
			(stroke
				(width 0)
				(type default)
			)
			(fill yes)
			(layer "F.SilkS")
		)
		(fp_line
			(start 2.500122 2.999994)
			(end -2.500122 2.999994)
			(stroke
				(width 0.1)
				(type default)
			)
			(layer "F.Fab")
		)
		(fp_line
			(start 2.500122 -2.999994)
			(end 2.500122 2.999994)
			(stroke
				(width 0.1)
				(type default)
			)
			(layer "F.Fab")
		)
		(fp_line
			(start -2.500122 2.999994)
			(end -2.500122 -2.999994)
			(stroke
				(width 0.1)
				(type default)
			)
			(layer "F.Fab")
		)
		(fp_line
			(start -2.500122 -2.999994)
			(end 2.500122 -2.999994)
			(stroke
				(width 0.1)
				(type default)
			)
			(layer "F.Fab")
		)
		(fp_poly
			(pts
				(xy -4.218432 -2.783078) (xy -4.218432 -1.767078) (xy -3.202432 -2.275078)
			)
			(stroke
				(width 0)
				(type default)
			)
			(fill yes)
			(layer "F.Fab")
		)
		(pad "1" smd rect
			(at -2.400046 -2.275078 270)
			(size 0.2286 0.6096)
			(layers "F.Cu" "F.Mask" "F.Paste")
			(net "PVDDCR_CPU0_P1_VOS4")
		)
		(pad "2" smd rect
			(at -2.400046 -1.82499 270)
			(size 0.2286 0.6096)
			(layers "F.Cu" "F.Mask" "F.Paste")
			(net "GND")
		)
		(pad "3" smd rect
			(at -2.400046 -1.374902 270)
			(size 0.2286 0.6096)
			(layers "F.Cu" "F.Mask" "F.Paste")
			(net "PVDDCR_CPU0_P1_VCC4")
		)
		(pad "4" smd rect
			(at -2.400046 -0.925068 270)
			(size 0.2286 0.6096)
			(layers "F.Cu" "F.Mask" "F.Paste")
			(net "PVDDCR_CPU0_P1_PVCC")
		)
		(pad "5" smd rect
			(at -2.400046 -0.47498 270)
			(size 0.2286 0.6096)
			(layers "F.Cu" "F.Mask" "F.Paste")
			(net "GND")
		)
		(pad "6" smd rect
			(at -2.400046 -0.024892 270)
			(size 0.2286 0.6096)
			(layers "F.Cu" "F.Mask" "F.Paste")
			(net "NC_PVDDCR_CPU0_P1_GL1_4")
		)
		(pad "7_9-20_24" smd circle
			(at 0 1.150112 270)
			(size 0 0)
			(layers "F.Cu" "F.Mask" "F.Paste")
			(net "GND")
		)
		(pad "10_19" smd rect
			(at 0 2.899918 270)
			(size 0.6096 4.318)
			(layers "F.Cu" "F.Mask" "F.Paste")
			(net "SW_PVDDCR_CPU0_P1_SW4")
		)
		(pad "25_29" smd rect
			(at 1.549908 -1.279906 90)
			(size 2.0574 2.3114)
			(layers "F.Cu" "F.Mask" "F.Paste")
			(net "SW_P12V_AUX_PVDDCR_CPU0_P1_FLT")
		)
		(pad "30" smd rect
			(at 2.05994 -2.899918 180)
			(size 0.2286 0.6096)
			(layers "F.Cu" "F.Mask" "F.Paste")
			(net "SW_P12V_AUX_PVDDCR_CPU0_P1_FLT")
		)
		(pad "31" smd rect
			(at 1.610106 -2.899918 180)
			(size 0.2286 0.6096)
			(layers "F.Cu" "F.Mask" "F.Paste")
			(net "NC_PVDDCR_CPU0_P1_DNC4")
		)
		(pad "32" smd rect
			(at 1.160018 -2.899918 180)
			(size 0.2286 0.6096)
			(layers "F.Cu" "F.Mask" "F.Paste")
			(net "SW_PVDDCR_CPU0_P1_PH4")
		)
		(pad "33" smd rect
			(at 0.70993 -2.899918 180)
			(size 0.2286 0.6096)
			(layers "F.Cu" "F.Mask" "F.Paste")
			(net "SW_PVDDCR_CPU0_P1_BOOT4")
		)
		(pad "34" smd rect
			(at 0.260096 -2.899918 180)
			(size 0.2286 0.6096)
			(layers "F.Cu" "F.Mask" "F.Paste")
			(net "PVDDCR_CPU0_P1_PWM4")
		)
		(pad "35" smd rect
			(at -0.189992 -2.899918 180)
			(size 0.2286 0.6096)
			(layers "F.Cu" "F.Mask" "F.Paste")
			(net "PVDDCR_CPU0_P1_VCC4")
		)
		(pad "36" smd rect
			(at -0.64008 -2.899918 180)
			(size 0.2286 0.6096)
			(layers "F.Cu" "F.Mask" "F.Paste")
			(net "PVDDCR_CPU0_P1_TEMP0")
		)
		(pad "37" smd rect
			(at -1.089914 -2.899918 180)
			(size 0.2286 0.6096)
			(layers "F.Cu" "F.Mask" "F.Paste")
			(net "PVDDCR_CPU0_P1_LSET4")
		)
		(pad "38" smd rect
			(at -1.540002 -2.899918 180)
			(size 0.2286 0.6096)
			(layers "F.Cu" "F.Mask" "F.Paste")
			(net "PVDDCR_CPU0_P1_IMON4")
		)
		(pad "39" smd rect
			(at -1.99009 -2.899918 180)
			(size 0.2286 0.6096)
			(layers "F.Cu" "F.Mask" "F.Paste")
			(net "PVDDCR_CPU0_P1_VCCS")
		)
		(pad "40" smd rect
			(at -0.87503 -1.27508 180)
			(size 1.7526 1.9558)
			(layers "F.Cu" "F.Mask" "F.Paste")
			(net "GND")
		)
		(pad "41" smd rect
			(at -1.525016 0.249936 90)
			(size 0.3048 0.4572)
			(layers "F.Cu" "F.Mask" "F.Paste")
			(net "NC_PVDDCR_CPU0_P1_GL2_4")
		)
		(zone
			(layer "F.Cu")
			(hatch none 0.5)
			(connect_pads
				(clearance 0)
			)
			(min_thickness 0.25)
			(keepout
				(tracks not_allowed)
				(vias allowed)
				(pads allowed)
				(copperpour not_allowed)
				(footprints allowed)
			)
			(placement
				(enabled no)
				(sheetname "")
			)
			(fill
				(thermal_gap 0.5)
				(thermal_bridge_width 0.5)
				(island_removal_mode 0)
			)
			(polygon
				(pts
					(xy 109.956092 -180.716174) (xy 109.956092 -180.42255) (xy 104.955848 -180.42255) (xy 104.955848 -180.716174)
					(xy 105.24617 -180.716174) (xy 109.66577 -180.716174)
				)
			)
		)
		(zone
			(layer "F.Cu")
			(hatch none 0.5)
			(connect_pads
				(clearance 0)
			)
			(min_thickness 0.25)
			(keepout
				(tracks not_allowed)
				(vias allowed)
				(pads allowed)
				(copperpour not_allowed)
				(footprints allowed)
			)
			(placement
				(enabled no)
				(sheetname "")
			)
			(fill
				(thermal_gap 0.5)
				(thermal_bridge_width 0.5)
				(island_removal_mode 0)
			)
			(polygon
				(pts
					(xy 107.4039 -177.925476) (xy 107.4039 -175.868076) (xy 109.2581 -175.868076) (xy 109.2581 -176.109122)
					(xy 109.500416 -176.109122) (xy 109.500416 -175.627538) (xy 105.57637 -175.627538) (xy 105.57637 -175.81245)
					(xy 107.112562 -175.81245) (xy 107.112562 -177.97145) (xy 104.955848 -177.97145) (xy 104.955848 -178.221132)
					(xy 107.122468 -178.221132) (xy 107.4039 -177.9397)
				)
			)
		)
	)
)
